(kicad_pcb
	(version 20260206)
	(generator "pcbnew")
	(generator_version "10.0")
	(general
		(thickness 1.21888)
		(legacy_teardrops no)
	)
	(paper "A4")
	(title_block
		(title "timecard-beta-v1 — TimeCard-DC-V1.PcbDoc")
		(comment 1 "Time Appliance Project (Time Card) / footprints 109-120 of 120")
	)
	(layers
		(0 "F.Cu" signal "TOP")
		(4 "In1.Cu" signal "SGND")
		(6 "In2.Cu" signal "IN1")
		(8 "In3.Cu" signal "IN2")
		(10 "In4.Cu" signal "SGND1")
		(2 "B.Cu" signal "BOTTOM")
		(9 "F.Adhes" user "F.Adhesive")
		(11 "B.Adhes" user "B.Adhesive")
		(13 "F.Paste" user "Top Paste")
		(15 "B.Paste" user "Bottom Paste")
		(5 "F.SilkS" user "Top Overlay")
		(7 "B.SilkS" user "Bottom Overlay")
		(1 "F.Mask" user "Top Solder")
		(3 "B.Mask" user "Bottom Solder")
		(17 "Dwgs.User" user "User.Drawings")
		(19 "Cmts.User" user "User.Comments")
		(21 "Eco1.User" user "User.Eco1")
		(23 "Eco2.User" user "User.Eco2")
		(25 "Edge.Cuts" user)
		(27 "Margin" user)
		(31 "F.CrtYd" user "Top Courtyard")
		(29 "B.CrtYd" user "Bottom Courtyard")
		(35 "F.Fab" user "Top Component Center")
		(33 "B.Fab" user "Bottom Component Center")
	)
	(footprint "Capacitors:CAPC1608X10N"
		(layer "F.Cu")
		(at 222.822595 102.8936 90)
		(property "Reference" "C3"
			(at -3.16 0.509345 90)
			(unlocked yes)
			(layer "F.SilkS")
			(effects
				(font
					(size 0.762 0.762)
					(thickness 0.2286)
				)
				(justify left bottom)
			)
		)
		(property "Value" "CAP_0603_0.01UF_50V"
			(at 12.98321 3.9751 0)
			(unlocked yes)
			(layer "F.SilkS")
			(hide yes)
			(effects
				(font
					(size 1.524 1.524)
					(thickness 0.254)
				)
				(justify left bottom)
			)
		)
		(sheetname "POWER")
		(sheetfile "POWER.kicad_sch")
		(duplicate_pad_numbers_are_jumpers no)
		(fp_line
			(start -0.635 -0.7112)
			(end 0.635 -0.7112)
			(stroke
				(width 0.1524)
				(type solid)
			)
			(layer "F.SilkS")
		)
		(fp_line
			(start -0.635 0.7112)
			(end 0.635 0.7112)
			(stroke
				(width 0.1524)
				(type solid)
			)
			(layer "F.SilkS")
		)
		(pad "1" smd rect
			(at -0.8 0 180)
			(size 0.95 1)
			(layers "F.Cu" "F.Mask" "F.Paste")
			(net "NetC3_1")
		)
		(pad "2" smd rect
			(at 0.8 0 180)
			(size 0.95 1)
			(layers "F.Cu" "F.Mask" "F.Paste")
			(net "NetC3_2")
		)
	)
	(footprint "Capacitors:CAPC2012X14N"
		(layer "F.Cu")
		(at 124.988595 79.8286 -90)
		(property "Reference" "C60"
			(at 1.5 -4.593345 90)
			(unlocked yes)
			(layer "F.SilkS")
			(effects
				(font
					(size 0.762 0.762)
					(thickness 0.2286)
				)
				(justify left bottom)
			)
		)
		(property "Value" "CAP_0805_10UF_25V"
			(at 3.52679 1.5875 0)
			(unlocked yes)
			(layer "F.SilkS")
			(hide yes)
			(effects
				(font
					(size 1.524 1.524)
					(thickness 0.254)
				)
				(justify left bottom)
			)
		)
		(sheetname "GPS_IMU_SENSORS")
		(sheetfile "GPS_IMU_SENSORS.kicad_sch")
		(duplicate_pad_numbers_are_jumpers no)
		(fp_line
			(start 0.762 0.9652)
			(end -0.762 0.9652)
			(stroke
				(width 0.1524)
				(type solid)
			)
			(layer "F.SilkS")
		)
		(fp_line
			(start 0.762 -0.9652)
			(end -0.762 -0.9652)
			(stroke
				(width 0.1524)
				(type solid)
			)
			(layer "F.SilkS")
		)
		(pad "1" smd rect
			(at -0.9 0)
			(size 1.45 1.15)
			(layers "F.Cu" "F.Mask" "F.Paste")
			(net "+5.0V")
		)
		(pad "2" smd rect
			(at 0.9 0)
			(size 1.45 1.15)
			(layers "F.Cu" "F.Mask" "F.Paste")
			(net "GND")
		)
	)
	(footprint "Capacitors:CAPC1005X06N"
		(layer "B.Cu")
		(at 119.190595 151.7886 90)
		(property "Reference" "C45"
			(at 2.835 -0.445345 270)
			(unlocked yes)
			(layer "B.SilkS")
			(effects
				(font
					(size 0.762 0.762)
					(thickness 0.2286)
				)
				(justify left bottom mirror)
			)
		)
		(property "Value" "CAP_0402_0.1UF_50V"
			(at -3.47599 0.2921 0)
			(unlocked yes)
			(layer "B.SilkS")
			(hide yes)
			(effects
				(font
					(size 1.524 1.524)
					(thickness 0.254)
				)
				(justify left bottom mirror)
			)
		)
		(sheetname "PCIe_JTAG")
		(sheetfile "PCIe_JTAG.kicad_sch")
		(duplicate_pad_numbers_are_jumpers no)
		(pad "1" smd rect
			(at -0.43 0)
			(size 0.64 0.68)
			(layers "B.Cu" "B.Mask" "B.Paste")
			(net "NetC45_1")
		)
		(pad "2" smd rect
			(at 0.43 0)
			(size 0.64 0.68)
			(layers "B.Cu" "B.Mask" "B.Paste")
			(net "PCIE_CLK_N")
		)
	)
	(footprint "Capacitors:CAPC1005X06N"
		(layer "B.Cu")
		(at 135.192595 151.7886 90)
		(property "Reference" "C53"
			(at 2.41349 0.046545 270)
			(unlocked yes)
			(layer "B.SilkS")
			(effects
				(font
					(size 0.762 0.762)
					(thickness 0.2286)
				)
				(justify left bottom mirror)
			)
		)
		(property "Value" "CAP_0402_0.1UF_50V"
			(at -3.47599 0.2921 0)
			(unlocked yes)
			(layer "B.SilkS")
			(hide yes)
			(effects
				(font
					(size 1.524 1.524)
					(thickness 0.254)
				)
				(justify left bottom mirror)
			)
		)
		(sheetname "PCIe_JTAG")
		(sheetfile "PCIe_JTAG.kicad_sch")
		(duplicate_pad_numbers_are_jumpers no)
		(pad "1" smd rect
			(at -0.43 0)
			(size 0.64 0.68)
			(layers "B.Cu" "B.Mask" "B.Paste")
			(net "NetC53_1")
		)
		(pad "2" smd rect
			(at 0.43 0)
			(size 0.64 0.68)
			(layers "B.Cu" "B.Mask" "B.Paste")
			(net "PCIE_TX3_N")
		)
	)
	(footprint "Capacitors:CAPC1005X06N"
		(layer "B.Cu")
		(at 130.112595 151.7886 90)
		(property "Reference" "C50"
			(at 2.41349 -0.766255 270)
			(unlocked yes)
			(layer "B.SilkS")
			(effects
				(font
					(size 0.762 0.762)
					(thickness 0.2286)
				)
				(justify left bottom mirror)
			)
		)
		(property "Value" "CAP_0402_0.1UF_50V"
			(at -3.47599 0.2921 0)
			(unlocked yes)
			(layer "B.SilkS")
			(hide yes)
			(effects
				(font
					(size 1.524 1.524)
					(thickness 0.254)
				)
				(justify left bottom mirror)
			)
		)
		(sheetname "PCIe_JTAG")
		(sheetfile "PCIe_JTAG.kicad_sch")
		(duplicate_pad_numbers_are_jumpers no)
		(pad "1" smd rect
			(at -0.43 0)
			(size 0.64 0.68)
			(layers "B.Cu" "B.Mask" "B.Paste")
			(net "NetC50_1")
		)
		(pad "2" smd rect
			(at 0.43 0)
			(size 0.64 0.68)
			(layers "B.Cu" "B.Mask" "B.Paste")
			(net "PCIE_TX2_P")
		)
	)
	(footprint "Capacitors:CAPC1005X06N"
		(layer "B.Cu")
		(at 131.001595 151.7886 90)
		(property "Reference" "C51"
			(at 2.41349 0.148145 270)
			(unlocked yes)
			(layer "B.SilkS")
			(effects
				(font
					(size 0.762 0.762)
					(thickness 0.2286)
				)
				(justify left bottom mirror)
			)
		)
		(property "Value" "CAP_0402_0.1UF_50V"
			(at -3.47599 0.2921 0)
			(unlocked yes)
			(layer "B.SilkS")
			(hide yes)
			(effects
				(font
					(size 1.524 1.524)
					(thickness 0.254)
				)
				(justify left bottom mirror)
			)
		)
		(sheetname "PCIe_JTAG")
		(sheetfile "PCIe_JTAG.kicad_sch")
		(duplicate_pad_numbers_are_jumpers no)
		(pad "1" smd rect
			(at -0.43 0)
			(size 0.64 0.68)
			(layers "B.Cu" "B.Mask" "B.Paste")
			(net "NetC51_1")
		)
		(pad "2" smd rect
			(at 0.43 0)
			(size 0.64 0.68)
			(layers "B.Cu" "B.Mask" "B.Paste")
			(net "PCIE_TX2_N")
		)
	)
	(footprint "Capacitors:CAPC1005X06N"
		(layer "B.Cu")
		(at 118.174595 151.7886 90)
		(property "Reference" "C44"
			(at 2.885 -1.204345 270)
			(unlocked yes)
			(layer "B.SilkS")
			(effects
				(font
					(size 0.762 0.762)
					(thickness 0.2286)
				)
				(justify left bottom mirror)
			)
		)
		(property "Value" "CAP_0402_0.1UF_50V"
			(at -3.47599 0.2921 0)
			(unlocked yes)
			(layer "B.SilkS")
			(hide yes)
			(effects
				(font
					(size 1.524 1.524)
					(thickness 0.254)
				)
				(justify left bottom mirror)
			)
		)
		(sheetname "PCIe_JTAG")
		(sheetfile "PCIe_JTAG.kicad_sch")
		(duplicate_pad_numbers_are_jumpers no)
		(pad "1" smd rect
			(at -0.43 0)
			(size 0.64 0.68)
			(layers "B.Cu" "B.Mask" "B.Paste")
			(net "NetC44_1")
		)
		(pad "2" smd rect
			(at 0.43 0)
			(size 0.64 0.68)
			(layers "B.Cu" "B.Mask" "B.Paste")
			(net "PCIE_CLK_P")
		)
	)
	(footprint "Capacitors:CAPC1005X06N"
		(layer "B.Cu")
		(at 127.191595 151.7886 90)
		(property "Reference" "C49"
			(at 2.41349 -0.156655 270)
			(unlocked yes)
			(layer "B.SilkS")
			(effects
				(font
					(size 0.762 0.762)
					(thickness 0.2286)
				)
				(justify left bottom mirror)
			)
		)
		(property "Value" "CAP_0402_0.1UF_50V"
			(at -3.47599 0.2921 0)
			(unlocked yes)
			(layer "B.SilkS")
			(hide yes)
			(effects
				(font
					(size 1.524 1.524)
					(thickness 0.254)
				)
				(justify left bottom mirror)
			)
		)
		(sheetname "PCIe_JTAG")
		(sheetfile "PCIe_JTAG.kicad_sch")
		(duplicate_pad_numbers_are_jumpers no)
		(pad "1" smd rect
			(at -0.43 0)
			(size 0.64 0.68)
			(layers "B.Cu" "B.Mask" "B.Paste")
			(net "NetC49_1")
		)
		(pad "2" smd rect
			(at 0.43 0)
			(size 0.64 0.68)
			(layers "B.Cu" "B.Mask" "B.Paste")
			(net "PCIE_TX1_N")
		)
	)
	(footprint "Capacitors:CAPC1005X06N"
		(layer "B.Cu")
		(at 134.176595 151.7886 90)
		(property "Reference" "C52"
			(at 2.41349 -0.613855 270)
			(unlocked yes)
			(layer "B.SilkS")
			(effects
				(font
					(size 0.762 0.762)
					(thickness 0.2286)
				)
				(justify left bottom mirror)
			)
		)
		(property "Value" "CAP_0402_0.1UF_50V"
			(at -3.47599 0.2921 0)
			(unlocked yes)
			(layer "B.SilkS")
			(hide yes)
			(effects
				(font
					(size 1.524 1.524)
					(thickness 0.254)
				)
				(justify left bottom mirror)
			)
		)
		(sheetname "PCIe_JTAG")
		(sheetfile "PCIe_JTAG.kicad_sch")
		(duplicate_pad_numbers_are_jumpers no)
		(pad "1" smd rect
			(at -0.43 0)
			(size 0.64 0.68)
			(layers "B.Cu" "B.Mask" "B.Paste")
			(net "NetC52_1")
		)
		(pad "2" smd rect
			(at 0.43 0)
			(size 0.64 0.68)
			(layers "B.Cu" "B.Mask" "B.Paste")
			(net "PCIE_TX3_P")
		)
	)
	(footprint "Capacitors:CAPC1005X06N"
		(layer "B.Cu")
		(at 126.175595 151.7886 90)
		(property "Reference" "C48"
			(at 2.41349 -0.867855 270)
			(unlocked yes)
			(layer "B.SilkS")
			(effects
				(font
					(size 0.762 0.762)
					(thickness 0.2286)
				)
				(justify left bottom mirror)
			)
		)
		(property "Value" "CAP_0402_0.1UF_50V"
			(at -3.47599 0.2921 0)
			(unlocked yes)
			(layer "B.SilkS")
			(hide yes)
			(effects
				(font
					(size 1.524 1.524)
					(thickness 0.254)
				)
				(justify left bottom mirror)
			)
		)
		(sheetname "PCIe_JTAG")
		(sheetfile "PCIe_JTAG.kicad_sch")
		(duplicate_pad_numbers_are_jumpers no)
		(pad "1" smd rect
			(at -0.43 0)
			(size 0.64 0.68)
			(layers "B.Cu" "B.Mask" "B.Paste")
			(net "NetC48_1")
		)
		(pad "2" smd rect
			(at 0.43 0)
			(size 0.64 0.68)
			(layers "B.Cu" "B.Mask" "B.Paste")
			(net "PCIE_TX1_P")
		)
	)
	(footprint "Capacitors:CAPC1005X06N"
		(layer "B.Cu")
		(at 122.289395 151.7886 90)
		(property "Reference" "C47"
			(at 2.41349 0.097345 270)
			(unlocked yes)
			(layer "B.SilkS")
			(effects
				(font
					(size 0.762 0.762)
					(thickness 0.2286)
				)
				(justify left bottom mirror)
			)
		)
		(property "Value" "CAP_0402_0.1UF_50V"
			(at -3.47599 0.2921 0)
			(unlocked yes)
			(layer "B.SilkS")
			(hide yes)
			(effects
				(font
					(size 1.524 1.524)
					(thickness 0.254)
				)
				(justify left bottom mirror)
			)
		)
		(sheetname "PCIe_JTAG")
		(sheetfile "PCIe_JTAG.kicad_sch")
		(duplicate_pad_numbers_are_jumpers no)
		(pad "1" smd rect
			(at -0.43 0)
			(size 0.64 0.68)
			(layers "B.Cu" "B.Mask" "B.Paste")
			(net "NetC47_1")
		)
		(pad "2" smd rect
			(at 0.43 0)
			(size 0.64 0.68)
			(layers "B.Cu" "B.Mask" "B.Paste")
			(net "PCIE_TX0_N")
		)
	)
	(footprint "Capacitors:CAPC1005X06N"
		(layer "B.Cu")
		(at 121.197195 151.7886 90)
		(property "Reference" "C46"
			(at 2.41349 -0.563055 270)
			(unlocked yes)
			(layer "B.SilkS")
			(effects
				(font
					(size 0.762 0.762)
					(thickness 0.2286)
				)
				(justify left bottom mirror)
			)
		)
		(property "Value" "CAP_0402_0.1UF_50V"
			(at -3.47599 0.2921 0)
			(unlocked yes)
			(layer "B.SilkS")
			(hide yes)
			(effects
				(font
					(size 1.524 1.524)
					(thickness 0.254)
				)
				(justify left bottom mirror)
			)
		)
		(sheetname "PCIe_JTAG")
		(sheetfile "PCIe_JTAG.kicad_sch")
		(duplicate_pad_numbers_are_jumpers no)
		(pad "1" smd rect
			(at -0.43 0)
			(size 0.64 0.68)
			(layers "B.Cu" "B.Mask" "B.Paste")
			(net "NetC46_1")
		)
		(pad "2" smd rect
			(at 0.43 0)
			(size 0.64 0.68)
			(layers "B.Cu" "B.Mask" "B.Paste")
			(net "PCIE_TX0_P")
		)
	)
)
